(kicad_pcb
	(version 20260206)
	(generator "pcbnew")
	(generator_version "10.0")
	(general
		(thickness 1.6)
		(legacy_teardrops no)
	)
	(paper "A4")
	(title_block
		(title "04192023_DAF0TMB3IC0_F0TG_MB_C_brd_V02_OCP.brd")
		(comment 1 "Grand Teton / footprints 5291-5297 of 8354")
	)
	(layers
		(0 "F.Cu" signal "TOP")
		(4 "In1.Cu" signal "GND")
		(6 "In2.Cu" signal "IN1")
		(8 "In3.Cu" signal "GND1")
		(10 "In4.Cu" signal "IN2")
		(12 "In5.Cu" signal "GND2")
		(14 "In6.Cu" signal "IN3")
		(16 "In7.Cu" signal "GND3")
		(18 "In8.Cu" signal "VCC")
		(20 "In9.Cu" signal "VCC1")
		(22 "In10.Cu" signal "GND4")
		(24 "In11.Cu" signal "IN4")
		(26 "In12.Cu" signal "GND5")
		(28 "In13.Cu" signal "IN5")
		(30 "In14.Cu" signal "GND6")
		(32 "In15.Cu" signal "IN6")
		(34 "In16.Cu" signal "GND7")
		(2 "B.Cu" signal "BOTTOM")
		(9 "F.Adhes" user "F.Adhesive")
		(11 "B.Adhes" user "B.Adhesive")
		(13 "F.Paste" user "Package Geometry/Pastemask Top")
		(15 "B.Paste" user "Package Geometry/Pastemask Bottom")
		(5 "F.SilkS" user "Ref Des/Silkscreen Top")
		(7 "B.SilkS" user "Ref Des/Silkscreen Bottom")
		(1 "F.Mask" user "Board Geometry/Soldermask Top")
		(3 "B.Mask" user "Board Geometry/Soldermask Bottom")
		(17 "Dwgs.User" user "User.Drawings")
		(19 "Cmts.User" user "User.Comments")
		(21 "Eco1.User" user "User.Eco1")
		(23 "Eco2.User" user "User.Eco2")
		(25 "Edge.Cuts" user "Board Geometry/Outline")
		(27 "Margin" user)
		(31 "F.CrtYd" user "Package Geometry/Place Bound Top")
		(29 "B.CrtYd" user "Package Geometry/Place Bound Bottom")
		(35 "F.Fab" user "Ref Des/Assembly Top")
		(33 "B.Fab" user "Ref Des/Assembly Bottom")
	)
	(footprint ""
		(layer "B.Cu")
		(at 304.419 -355.854 180)
		(property "Reference" "R8042"
			(at 0 0 0)
			(layer "B.SilkS")
			(hide yes)
			(effects
				(font
					(size 1.27 1.27)
				)
				(justify mirror)
			)
		)
		(property "Value" ""
			(at 0 0 0)
			(layer "B.Fab")
			(effects
				(font
					(size 1.27 1.27)
				)
				(justify mirror)
			)
		)
		(duplicate_pad_numbers_are_jumpers no)
		(fp_line
			(start 0.7874 0.4064)
			(end 0.7874 -0.4064)
			(stroke
				(width 0.1524)
				(type default)
			)
			(layer "B.SilkS")
		)
		(fp_line
			(start 0.7874 -0.4064)
			(end -0.7874 -0.4064)
			(stroke
				(width 0.1524)
				(type default)
			)
			(layer "B.SilkS")
		)
		(fp_line
			(start -0.7874 0.4064)
			(end 0.7874 0.4064)
			(stroke
				(width 0.1524)
				(type default)
			)
			(layer "B.SilkS")
		)
		(fp_line
			(start -0.7874 -0.4064)
			(end -0.7874 0.4064)
			(stroke
				(width 0.1524)
				(type default)
			)
			(layer "B.SilkS")
		)
		(fp_line
			(start 0.67945 0.3048)
			(end 0.67945 -0.305054)
			(stroke
				(width 0.1)
				(type default)
			)
			(layer "B.Fab")
		)
		(fp_line
			(start 0.67945 -0.305054)
			(end 0.12065 -0.305054)
			(stroke
				(width 0.1)
				(type default)
			)
			(layer "B.Fab")
		)
		(fp_line
			(start 0.12065 0.3048)
			(end 0.67945 0.3048)
			(stroke
				(width 0.1)
				(type default)
			)
			(layer "B.Fab")
		)
		(fp_line
			(start 0.12065 0.2794)
			(end 0.12065 0.3048)
			(stroke
				(width 0.1)
				(type default)
			)
			(layer "B.Fab")
		)
		(fp_line
			(start 0.12065 -0.2794)
			(end -0.12065 -0.2794)
			(stroke
				(width 0.1)
				(type default)
			)
			(layer "B.Fab")
		)
		(fp_line
			(start 0.12065 -0.305054)
			(end 0.12065 -0.2794)
			(stroke
				(width 0.1)
				(type default)
			)
			(layer "B.Fab")
		)
		(fp_line
			(start -0.120396 0.3048)
			(end -0.120396 0.2794)
			(stroke
				(width 0.1)
				(type default)
			)
			(layer "B.Fab")
		)
		(fp_line
			(start -0.120396 0.2794)
			(end 0.12065 0.2794)
			(stroke
				(width 0.1)
				(type default)
			)
			(layer "B.Fab")
		)
		(fp_line
			(start -0.12065 -0.2794)
			(end -0.12065 -0.3048)
			(stroke
				(width 0.1)
				(type default)
			)
			(layer "B.Fab")
		)
		(fp_line
			(start -0.12065 -0.3048)
			(end -0.67945 -0.3048)
			(stroke
				(width 0.1)
				(type default)
			)
			(layer "B.Fab")
		)
		(fp_line
			(start -0.67945 0.3048)
			(end -0.120396 0.3048)
			(stroke
				(width 0.1)
				(type default)
			)
			(layer "B.Fab")
		)
		(fp_line
			(start -0.67945 -0.3048)
			(end -0.67945 0.3048)
			(stroke
				(width 0.1)
				(type default)
			)
			(layer "B.Fab")
		)
		(pad "1" smd circle
			(at 0.40005 0)
			(size 0 0)
			(layers "B.Cu" "B.Mask" "B.Paste")
			(net "SVID_PVDDCR_CPU1_P0_SVTO")
		)
		(pad "2" smd circle
			(at -0.40005 0)
			(size 0 0)
			(layers "B.Cu" "B.Mask" "B.Paste")
			(net "GND")
		)
	)
	(footprint ""
		(layer "B.Cu")
		(at 114.607848 -171.785534 -90)
		(property "Reference" "PC329_1"
			(at 0 0 90)
			(layer "B.SilkS")
			(hide yes)
			(effects
				(font
					(size 1.27 1.27)
				)
				(justify mirror)
			)
		)
		(property "Value" ""
			(at 0 0 90)
			(layer "B.Fab")
			(effects
				(font
					(size 1.27 1.27)
				)
				(justify mirror)
			)
		)
		(duplicate_pad_numbers_are_jumpers no)
		(fp_line
			(start -1.524 0.762)
			(end 1.524 0.762)
			(stroke
				(width 0.1524)
				(type default)
			)
			(layer "B.SilkS")
		)
		(fp_line
			(start 1.524 0.762)
			(end 1.524 -0.762)
			(stroke
				(width 0.1524)
				(type default)
			)
			(layer "B.SilkS")
		)
		(fp_line
			(start -1.524 -0.762)
			(end -1.524 0.762)
			(stroke
				(width 0.1524)
				(type default)
			)
			(layer "B.SilkS")
		)
		(fp_line
			(start 1.524 -0.762)
			(end -1.524 -0.762)
			(stroke
				(width 0.1524)
				(type default)
			)
			(layer "B.SilkS")
		)
		(fp_line
			(start -1.1049 0.724916)
			(end -1.1049 -0.724916)
			(stroke
				(width 0.1)
				(type default)
			)
			(layer "B.Fab")
		)
		(fp_line
			(start 1.1049 0.724916)
			(end -1.1049 0.724916)
			(stroke
				(width 0.1)
				(type default)
			)
			(layer "B.Fab")
		)
		(fp_line
			(start -1.1049 -0.724916)
			(end 1.1049 -0.724916)
			(stroke
				(width 0.1)
				(type default)
			)
			(layer "B.Fab")
		)
		(fp_line
			(start 1.1049 -0.724916)
			(end 1.1049 0.724916)
			(stroke
				(width 0.1)
				(type default)
			)
			(layer "B.Fab")
		)
		(pad "1" smd rect
			(at 0.889 0 270)
			(size 1.016 1.27)
			(layers "B.Cu" "B.Mask" "B.Paste")
			(net "SW_P12V_AUX_PVDDCR_SOC_P1_FLT")
		)
		(pad "2" smd rect
			(at -0.889 0 270)
			(size 1.016 1.27)
			(layers "B.Cu" "B.Mask" "B.Paste")
			(net "GND")
		)
	)
	(footprint ""
		(layer "B.Cu")
		(at 328.699876 -66.708782 90)
		(property "Reference" "R3088"
			(at 0 0 90)
			(layer "B.SilkS")
			(hide yes)
			(effects
				(font
					(size 1.27 1.27)
				)
				(justify mirror)
			)
		)
		(property "Value" ""
			(at 0 0 90)
			(layer "B.Fab")
			(effects
				(font
					(size 1.27 1.27)
				)
				(justify mirror)
			)
		)
		(duplicate_pad_numbers_are_jumpers no)
		(fp_line
			(start 0.7874 -0.4064)
			(end -0.7874 -0.4064)
			(stroke
				(width 0.1524)
				(type default)
			)
			(layer "B.SilkS")
		)
		(fp_line
			(start -0.7874 -0.4064)
			(end -0.7874 0.4064)
			(stroke
				(width 0.1524)
				(type default)
			)
			(layer "B.SilkS")
		)
		(fp_line
			(start 0.7874 0.4064)
			(end 0.7874 -0.4064)
			(stroke
				(width 0.1524)
				(type default)
			)
			(layer "B.SilkS")
		)
		(fp_line
			(start -0.7874 0.4064)
			(end 0.7874 0.4064)
			(stroke
				(width 0.1524)
				(type default)
			)
			(layer "B.SilkS")
		)
		(fp_line
			(start 0.67945 -0.305054)
			(end 0.12065 -0.305054)
			(stroke
				(width 0.1)
				(type default)
			)
			(layer "B.Fab")
		)
		(fp_line
			(start 0.12065 -0.305054)
			(end 0.12065 -0.2794)
			(stroke
				(width 0.1)
				(type default)
			)
			(layer "B.Fab")
		)
		(fp_line
			(start -0.12065 -0.3048)
			(end -0.67945 -0.3048)
			(stroke
				(width 0.1)
				(type default)
			)
			(layer "B.Fab")
		)
		(fp_line
			(start -0.67945 -0.3048)
			(end -0.67945 0.3048)
			(stroke
				(width 0.1)
				(type default)
			)
			(layer "B.Fab")
		)
		(fp_line
			(start 0.12065 -0.2794)
			(end -0.12065 -0.2794)
			(stroke
				(width 0.1)
				(type default)
			)
			(layer "B.Fab")
		)
		(fp_line
			(start -0.12065 -0.2794)
			(end -0.12065 -0.3048)
			(stroke
				(width 0.1)
				(type default)
			)
			(layer "B.Fab")
		)
		(fp_line
			(start 0.12065 0.2794)
			(end 0.12065 0.3048)
			(stroke
				(width 0.1)
				(type default)
			)
			(layer "B.Fab")
		)
		(fp_line
			(start -0.120396 0.2794)
			(end 0.12065 0.2794)
			(stroke
				(width 0.1)
				(type default)
			)
			(layer "B.Fab")
		)
		(fp_line
			(start 0.67945 0.3048)
			(end 0.67945 -0.305054)
			(stroke
				(width 0.1)
				(type default)
			)
			(layer "B.Fab")
		)
		(fp_line
			(start 0.12065 0.3048)
			(end 0.67945 0.3048)
			(stroke
				(width 0.1)
				(type default)
			)
			(layer "B.Fab")
		)
		(fp_line
			(start -0.120396 0.3048)
			(end -0.120396 0.2794)
			(stroke
				(width 0.1)
				(type default)
			)
			(layer "B.Fab")
		)
		(fp_line
			(start -0.67945 0.3048)
			(end -0.120396 0.3048)
			(stroke
				(width 0.1)
				(type default)
			)
			(layer "B.Fab")
		)
		(pad "1" smd circle
			(at 0.40005 0 270)
			(size 0 0)
			(layers "B.Cu" "B.Mask" "B.Paste")
			(net "LED_PWRGD_PVDDCR_CPU1_P0_R")
		)
		(pad "2" smd circle
			(at -0.40005 0 270)
			(size 0 0)
			(layers "B.Cu" "B.Mask" "B.Paste")
			(net "P3V3_AUX")
		)
	)
	(footprint ""
		(layer "B.Cu")
		(at 385.256278 -137.535158 90)
		(property "Reference" "PR316"
			(at 0 0 90)
			(layer "B.SilkS")
			(hide yes)
			(effects
				(font
					(size 1.27 1.27)
				)
				(justify mirror)
			)
		)
		(property "Value" ""
			(at 0 0 90)
			(layer "B.Fab")
			(effects
				(font
					(size 1.27 1.27)
				)
				(justify mirror)
			)
		)
		(duplicate_pad_numbers_are_jumpers no)
		(fp_line
			(start 0.7874 -0.4064)
			(end -0.7874 -0.4064)
			(stroke
				(width 0.1524)
				(type default)
			)
			(layer "B.SilkS")
		)
		(fp_line
			(start -0.7874 -0.4064)
			(end -0.7874 0.4064)
			(stroke
				(width 0.1524)
				(type default)
			)
			(layer "B.SilkS")
		)
		(fp_line
			(start 0.7874 0.4064)
			(end 0.7874 -0.4064)
			(stroke
				(width 0.1524)
				(type default)
			)
			(layer "B.SilkS")
		)
		(fp_line
			(start -0.7874 0.4064)
			(end 0.7874 0.4064)
			(stroke
				(width 0.1524)
				(type default)
			)
			(layer "B.SilkS")
		)
		(fp_line
			(start 0.67945 -0.305054)
			(end 0.12065 -0.305054)
			(stroke
				(width 0.1)
				(type default)
			)
			(layer "B.Fab")
		)
		(fp_line
			(start 0.12065 -0.305054)
			(end 0.12065 -0.2794)
			(stroke
				(width 0.1)
				(type default)
			)
			(layer "B.Fab")
		)
		(fp_line
			(start -0.12065 -0.3048)
			(end -0.67945 -0.3048)
			(stroke
				(width 0.1)
				(type default)
			)
			(layer "B.Fab")
		)
		(fp_line
			(start -0.67945 -0.3048)
			(end -0.67945 0.3048)
			(stroke
				(width 0.1)
				(type default)
			)
			(layer "B.Fab")
		)
		(fp_line
			(start 0.12065 -0.2794)
			(end -0.12065 -0.2794)
			(stroke
				(width 0.1)
				(type default)
			)
			(layer "B.Fab")
		)
		(fp_line
			(start -0.12065 -0.2794)
			(end -0.12065 -0.3048)
			(stroke
				(width 0.1)
				(type default)
			)
			(layer "B.Fab")
		)
		(fp_line
			(start 0.12065 0.2794)
			(end 0.12065 0.3048)
			(stroke
				(width 0.1)
				(type default)
			)
			(layer "B.Fab")
		)
		(fp_line
			(start -0.120396 0.2794)
			(end 0.12065 0.2794)
			(stroke
				(width 0.1)
				(type default)
			)
			(layer "B.Fab")
		)
		(fp_line
			(start 0.67945 0.3048)
			(end 0.67945 -0.305054)
			(stroke
				(width 0.1)
				(type default)
			)
			(layer "B.Fab")
		)
		(fp_line
			(start 0.12065 0.3048)
			(end 0.67945 0.3048)
			(stroke
				(width 0.1)
				(type default)
			)
			(layer "B.Fab")
		)
		(fp_line
			(start -0.120396 0.3048)
			(end -0.120396 0.2794)
			(stroke
				(width 0.1)
				(type default)
			)
			(layer "B.Fab")
		)
		(fp_line
			(start -0.67945 0.3048)
			(end -0.120396 0.3048)
			(stroke
				(width 0.1)
				(type default)
			)
			(layer "B.Fab")
		)
		(pad "1" smd circle
			(at 0.40005 0 270)
			(size 0 0)
			(layers "B.Cu" "B.Mask" "B.Paste")
			(net "PVDDCR_CPU0_P0_VCC")
		)
		(pad "2" smd circle
			(at -0.40005 0 270)
			(size 0 0)
			(layers "B.Cu" "B.Mask" "B.Paste")
			(net "P3V3_AUX")
		)
	)
	(footprint ""
		(layer "B.Cu")
		(at 346.373958 -265.045952)
		(property "Reference" "C2612"
			(at 0 0 0)
			(layer "B.SilkS")
			(hide yes)
			(effects
				(font
					(size 1.27 1.27)
				)
				(justify mirror)
			)
		)
		(property "Value" ""
			(at 0 0 0)
			(layer "B.Fab")
			(effects
				(font
					(size 1.27 1.27)
				)
				(justify mirror)
			)
		)
		(duplicate_pad_numbers_are_jumpers no)
		(fp_line
			(start -0.7874 -0.4064)
			(end -0.7874 0.4064)
			(stroke
				(width 0.1524)
				(type default)
			)
			(layer "B.SilkS")
		)
		(fp_line
			(start -0.7874 0.4064)
			(end 0.7874 0.4064)
			(stroke
				(width 0.1524)
				(type default)
			)
			(layer "B.SilkS")
		)
		(fp_line
			(start 0.7874 -0.4064)
			(end -0.7874 -0.4064)
			(stroke
				(width 0.1524)
				(type default)
			)
			(layer "B.SilkS")
		)
		(fp_line
			(start 0.7874 0.4064)
			(end 0.7874 -0.4064)
			(stroke
				(width 0.1524)
				(type default)
			)
			(layer "B.SilkS")
		)
		(fp_line
			(start -0.67945 -0.3048)
			(end -0.67945 0.3048)
			(stroke
				(width 0.1)
				(type default)
			)
			(layer "B.Fab")
		)
		(fp_line
			(start -0.67945 0.3048)
			(end -0.120396 0.3048)
			(stroke
				(width 0.1)
				(type default)
			)
			(layer "B.Fab")
		)
		(fp_line
			(start -0.12065 -0.3048)
			(end -0.67945 -0.3048)
			(stroke
				(width 0.1)
				(type default)
			)
			(layer "B.Fab")
		)
		(fp_line
			(start -0.12065 -0.2794)
			(end -0.12065 -0.3048)
			(stroke
				(width 0.1)
				(type default)
			)
			(layer "B.Fab")
		)
		(fp_line
			(start -0.120396 0.2794)
			(end 0.12065 0.2794)
			(stroke
				(width 0.1)
				(type default)
			)
			(layer "B.Fab")
		)
		(fp_line
			(start -0.120396 0.3048)
			(end -0.120396 0.2794)
			(stroke
				(width 0.1)
				(type default)
			)
			(layer "B.Fab")
		)
		(fp_line
			(start 0.12065 -0.305054)
			(end 0.12065 -0.2794)
			(stroke
				(width 0.1)
				(type default)
			)
			(layer "B.Fab")
		)
		(fp_line
			(start 0.12065 -0.2794)
			(end -0.12065 -0.2794)
			(stroke
				(width 0.1)
				(type default)
			)
			(layer "B.Fab")
		)
		(fp_line
			(start 0.12065 0.2794)
			(end 0.12065 0.3048)
			(stroke
				(width 0.1)
				(type default)
			)
			(layer "B.Fab")
		)
		(fp_line
			(start 0.12065 0.3048)
			(end 0.67945 0.3048)
			(stroke
				(width 0.1)
				(type default)
			)
			(layer "B.Fab")
		)
		(fp_line
			(start 0.67945 -0.305054)
			(end 0.12065 -0.305054)
			(stroke
				(width 0.1)
				(type default)
			)
			(layer "B.Fab")
		)
		(fp_line
			(start 0.67945 0.3048)
			(end 0.67945 -0.305054)
			(stroke
				(width 0.1)
				(type default)
			)
			(layer "B.Fab")
		)
		(pad "1" smd circle
			(at 0.40005 0 180)
			(size 0 0)
			(layers "B.Cu" "B.Mask" "B.Paste")
			(net "PVDDIO_P0")
		)
		(pad "2" smd circle
			(at -0.40005 0 180)
			(size 0 0)
			(layers "B.Cu" "B.Mask" "B.Paste")
			(net "GND")
		)
	)
	(footprint ""
		(layer "B.Cu")
		(at 126.504446 -408.517344 90)
		(property "Reference" "C6731"
			(at 0 0 90)
			(layer "B.SilkS")
			(hide yes)
			(effects
				(font
					(size 1.27 1.27)
				)
				(justify mirror)
			)
		)
		(property "Value" ""
			(at 0 0 90)
			(layer "B.Fab")
			(effects
				(font
					(size 1.27 1.27)
				)
				(justify mirror)
			)
		)
		(duplicate_pad_numbers_are_jumpers no)
		(fp_line
			(start 0.299974 -0.150114)
			(end -0.299974 -0.150114)
			(stroke
				(width 0.1)
				(type default)
			)
			(layer "B.Fab")
		)
		(fp_line
			(start -0.299974 -0.150114)
			(end -0.299974 0.150114)
			(stroke
				(width 0.1)
				(type default)
			)
			(layer "B.Fab")
		)
		(fp_line
			(start 0.299974 0.150114)
			(end 0.299974 -0.150114)
			(stroke
				(width 0.1)
				(type default)
			)
			(layer "B.Fab")
		)
		(fp_line
			(start -0.299974 0.150114)
			(end 0.299974 0.150114)
			(stroke
				(width 0.1)
				(type default)
			)
			(layer "B.Fab")
		)
		(pad "1" smd rect
			(at 0.2667 0 270)
			(size 0.3048 0.381)
			(layers "B.Cu" "B.Mask" "B.Paste")
			(net "P5E_CPU1_P3_TX_BUF_C_DP<3>")
		)
		(pad "2" smd rect
			(at -0.2667 0 270)
			(size 0.3048 0.381)
			(layers "B.Cu" "B.Mask" "B.Paste")
			(net "P5E_CPU1_P3_TX_BUF_DP<3>")
		)
	)
	(footprint ""
		(layer "B.Cu")
		(at 195.390008 -126.833376 180)
		(property "Reference" "R1549"
			(at 0 0 0)
			(layer "B.SilkS")
			(hide yes)
			(effects
				(font
					(size 1.27 1.27)
				)
				(justify mirror)
			)
		)
		(property "Value" ""
			(at 0 0 0)
			(layer "B.Fab")
			(effects
				(font
					(size 1.27 1.27)
				)
				(justify mirror)
			)
		)
		(duplicate_pad_numbers_are_jumpers no)
		(fp_line
			(start 0.7874 0.4064)
			(end 0.7874 -0.4064)
			(stroke
				(width 0.1524)
				(type default)
			)
			(layer "B.SilkS")
		)
		(fp_line
			(start 0.7874 -0.4064)
			(end -0.7874 -0.4064)
			(stroke
				(width 0.1524)
				(type default)
			)
			(layer "B.SilkS")
		)
		(fp_line
			(start -0.7874 0.4064)
			(end 0.7874 0.4064)
			(stroke
				(width 0.1524)
				(type default)
			)
			(layer "B.SilkS")
		)
		(fp_line
			(start -0.7874 -0.4064)
			(end -0.7874 0.4064)
			(stroke
				(width 0.1524)
				(type default)
			)
			(layer "B.SilkS")
		)
		(fp_line
			(start 0.67945 0.3048)
			(end 0.67945 -0.305054)
			(stroke
				(width 0.1)
				(type default)
			)
			(layer "B.Fab")
		)
		(fp_line
			(start 0.67945 -0.305054)
			(end 0.12065 -0.305054)
			(stroke
				(width 0.1)
				(type default)
			)
			(layer "B.Fab")
		)
		(fp_line
			(start 0.12065 0.3048)
			(end 0.67945 0.3048)
			(stroke
				(width 0.1)
				(type default)
			)
			(layer "B.Fab")
		)
		(fp_line
			(start 0.12065 0.2794)
			(end 0.12065 0.3048)
			(stroke
				(width 0.1)
				(type default)
			)
			(layer "B.Fab")
		)
		(fp_line
			(start 0.12065 -0.2794)
			(end -0.12065 -0.2794)
			(stroke
				(width 0.1)
				(type default)
			)
			(layer "B.Fab")
		)
		(fp_line
			(start 0.12065 -0.305054)
			(end 0.12065 -0.2794)
			(stroke
				(width 0.1)
				(type default)
			)
			(layer "B.Fab")
		)
		(fp_line
			(start -0.120396 0.3048)
			(end -0.120396 0.2794)
			(stroke
				(width 0.1)
				(type default)
			)
			(layer "B.Fab")
		)
		(fp_line
			(start -0.120396 0.2794)
			(end 0.12065 0.2794)
			(stroke
				(width 0.1)
				(type default)
			)
			(layer "B.Fab")
		)
		(fp_line
			(start -0.12065 -0.2794)
			(end -0.12065 -0.3048)
			(stroke
				(width 0.1)
				(type default)
			)
			(layer "B.Fab")
		)
		(fp_line
			(start -0.12065 -0.3048)
			(end -0.67945 -0.3048)
			(stroke
				(width 0.1)
				(type default)
			)
			(layer "B.Fab")
		)
		(fp_line
			(start -0.67945 0.3048)
			(end -0.120396 0.3048)
			(stroke
				(width 0.1)
				(type default)
			)
			(layer "B.Fab")
		)
		(fp_line
			(start -0.67945 -0.3048)
			(end -0.67945 0.3048)
			(stroke
				(width 0.1)
				(type default)
			)
			(layer "B.Fab")
		)
		(pad "1" smd circle
			(at 0.40005 0)
			(size 0 0)
			(layers "B.Cu" "B.Mask" "B.Paste")
			(net "ESPI_CPU0_R1_D0")
		)
		(pad "2" smd circle
			(at -0.40005 0)
			(size 0 0)
			(layers "B.Cu" "B.Mask" "B.Paste")
			(net "ESPI_CPU0_D0")
		)
	)
)
